(kicad_pcb
	(version 20260206)
	(generator "pcbnew")
	(generator_version "10.0")
	(general
		(thickness 1.6)
		(legacy_teardrops no)
	)
	(paper "A4")
	(title_block
		(title "04192023_DAF0TMB3IC0_F0TG_MB_C_brd_V02_OCP.brd")
		(comment 1 "Grand Teton / footprints 6630-6639 of 8354")
	)
	(layers
		(0 "F.Cu" signal "TOP")
		(4 "In1.Cu" signal "GND")
		(6 "In2.Cu" signal "IN1")
		(8 "In3.Cu" signal "GND1")
		(10 "In4.Cu" signal "IN2")
		(12 "In5.Cu" signal "GND2")
		(14 "In6.Cu" signal "IN3")
		(16 "In7.Cu" signal "GND3")
		(18 "In8.Cu" signal "VCC")
		(20 "In9.Cu" signal "VCC1")
		(22 "In10.Cu" signal "GND4")
		(24 "In11.Cu" signal "IN4")
		(26 "In12.Cu" signal "GND5")
		(28 "In13.Cu" signal "IN5")
		(30 "In14.Cu" signal "GND6")
		(32 "In15.Cu" signal "IN6")
		(34 "In16.Cu" signal "GND7")
		(2 "B.Cu" signal "BOTTOM")
		(9 "F.Adhes" user "F.Adhesive")
		(11 "B.Adhes" user "B.Adhesive")
		(13 "F.Paste" user "Package Geometry/Pastemask Top")
		(15 "B.Paste" user "Package Geometry/Pastemask Bottom")
		(5 "F.SilkS" user "Ref Des/Silkscreen Top")
		(7 "B.SilkS" user "Ref Des/Silkscreen Bottom")
		(1 "F.Mask" user "Board Geometry/Soldermask Top")
		(3 "B.Mask" user "Board Geometry/Soldermask Bottom")
		(17 "Dwgs.User" user "User.Drawings")
		(19 "Cmts.User" user "User.Comments")
		(21 "Eco1.User" user "User.Eco1")
		(23 "Eco2.User" user "User.Eco2")
		(25 "Edge.Cuts" user "Board Geometry/Outline")
		(27 "Margin" user)
		(31 "F.CrtYd" user "Package Geometry/Place Bound Top")
		(29 "B.CrtYd" user "Package Geometry/Place Bound Bottom")
		(35 "F.Fab" user "Ref Des/Assembly Top")
		(33 "B.Fab" user "Ref Des/Assembly Bottom")
	)
	(footprint ""
		(layer "B.Cu")
		(at 319.467484 -338.934806 -90)
		(property "Reference" "PC126_3"
			(at 0 0 90)
			(layer "B.SilkS")
			(hide yes)
			(effects
				(font
					(size 1.27 1.27)
				)
				(justify mirror)
			)
		)
		(property "Value" ""
			(at 0 0 90)
			(layer "B.Fab")
			(effects
				(font
					(size 1.27 1.27)
				)
				(justify mirror)
			)
		)
		(duplicate_pad_numbers_are_jumpers no)
		(fp_line
			(start -1.524 0.762)
			(end 1.524 0.762)
			(stroke
				(width 0.1524)
				(type default)
			)
			(layer "B.SilkS")
		)
		(fp_line
			(start 1.524 0.762)
			(end 1.524 -0.762)
			(stroke
				(width 0.1524)
				(type default)
			)
			(layer "B.SilkS")
		)
		(fp_line
			(start -1.524 -0.762)
			(end -1.524 0.762)
			(stroke
				(width 0.1524)
				(type default)
			)
			(layer "B.SilkS")
		)
		(fp_line
			(start 1.524 -0.762)
			(end -1.524 -0.762)
			(stroke
				(width 0.1524)
				(type default)
			)
			(layer "B.SilkS")
		)
		(fp_line
			(start -1.1049 0.724916)
			(end -1.1049 -0.724916)
			(stroke
				(width 0.1)
				(type default)
			)
			(layer "B.Fab")
		)
		(fp_line
			(start 1.1049 0.724916)
			(end -1.1049 0.724916)
			(stroke
				(width 0.1)
				(type default)
			)
			(layer "B.Fab")
		)
		(fp_line
			(start -1.1049 -0.724916)
			(end 1.1049 -0.724916)
			(stroke
				(width 0.1)
				(type default)
			)
			(layer "B.Fab")
		)
		(fp_line
			(start 1.1049 -0.724916)
			(end 1.1049 0.724916)
			(stroke
				(width 0.1)
				(type default)
			)
			(layer "B.Fab")
		)
		(pad "1" smd rect
			(at 0.889 0 270)
			(size 1.016 1.27)
			(layers "B.Cu" "B.Mask" "B.Paste")
			(net "SW_P12V_AUX_PVDDCR_CPU1_P0_FLT")
		)
		(pad "2" smd rect
			(at -0.889 0 270)
			(size 1.016 1.27)
			(layers "B.Cu" "B.Mask" "B.Paste")
			(net "GND")
		)
	)
	(footprint ""
		(layer "B.Cu")
		(at 110.808008 -171.775374 -90)
		(property "Reference" "PC334_1"
			(at 0 0 90)
			(layer "B.SilkS")
			(hide yes)
			(effects
				(font
					(size 1.27 1.27)
				)
				(justify mirror)
			)
		)
		(property "Value" ""
			(at 0 0 90)
			(layer "B.Fab")
			(effects
				(font
					(size 1.27 1.27)
				)
				(justify mirror)
			)
		)
		(duplicate_pad_numbers_are_jumpers no)
		(fp_line
			(start -1.524 0.762)
			(end 1.524 0.762)
			(stroke
				(width 0.1524)
				(type default)
			)
			(layer "B.SilkS")
		)
		(fp_line
			(start 1.524 0.762)
			(end 1.524 -0.762)
			(stroke
				(width 0.1524)
				(type default)
			)
			(layer "B.SilkS")
		)
		(fp_line
			(start -1.524 -0.762)
			(end -1.524 0.762)
			(stroke
				(width 0.1524)
				(type default)
			)
			(layer "B.SilkS")
		)
		(fp_line
			(start 1.524 -0.762)
			(end -1.524 -0.762)
			(stroke
				(width 0.1524)
				(type default)
			)
			(layer "B.SilkS")
		)
		(fp_line
			(start -1.1049 0.724916)
			(end -1.1049 -0.724916)
			(stroke
				(width 0.1)
				(type default)
			)
			(layer "B.Fab")
		)
		(fp_line
			(start 1.1049 0.724916)
			(end -1.1049 0.724916)
			(stroke
				(width 0.1)
				(type default)
			)
			(layer "B.Fab")
		)
		(fp_line
			(start -1.1049 -0.724916)
			(end 1.1049 -0.724916)
			(stroke
				(width 0.1)
				(type default)
			)
			(layer "B.Fab")
		)
		(fp_line
			(start 1.1049 -0.724916)
			(end 1.1049 0.724916)
			(stroke
				(width 0.1)
				(type default)
			)
			(layer "B.Fab")
		)
		(pad "1" smd rect
			(at 0.889 0 270)
			(size 1.016 1.27)
			(layers "B.Cu" "B.Mask" "B.Paste")
			(net "SW_P12V_AUX_PVDDCR_SOC_P1_FLT")
		)
		(pad "2" smd rect
			(at -0.889 0 270)
			(size 1.016 1.27)
			(layers "B.Cu" "B.Mask" "B.Paste")
			(net "GND")
		)
	)
	(footprint ""
		(layer "B.Cu")
		(at 231.0511 -327.21169)
		(property "Reference" "R1255"
			(at 0 0 0)
			(layer "B.SilkS")
			(hide yes)
			(effects
				(font
					(size 1.27 1.27)
				)
				(justify mirror)
			)
		)
		(property "Value" ""
			(at 0 0 0)
			(layer "B.Fab")
			(effects
				(font
					(size 1.27 1.27)
				)
				(justify mirror)
			)
		)
		(duplicate_pad_numbers_are_jumpers no)
		(fp_line
			(start -0.7874 -0.4064)
			(end -0.7874 0.4064)
			(stroke
				(width 0.1524)
				(type default)
			)
			(layer "B.SilkS")
		)
		(fp_line
			(start -0.7874 0.4064)
			(end 0.7874 0.4064)
			(stroke
				(width 0.1524)
				(type default)
			)
			(layer "B.SilkS")
		)
		(fp_line
			(start 0.7874 -0.4064)
			(end -0.7874 -0.4064)
			(stroke
				(width 0.1524)
				(type default)
			)
			(layer "B.SilkS")
		)
		(fp_line
			(start 0.7874 0.4064)
			(end 0.7874 -0.4064)
			(stroke
				(width 0.1524)
				(type default)
			)
			(layer "B.SilkS")
		)
		(fp_line
			(start -0.67945 -0.3048)
			(end -0.67945 0.3048)
			(stroke
				(width 0.1)
				(type default)
			)
			(layer "B.Fab")
		)
		(fp_line
			(start -0.67945 0.3048)
			(end -0.120396 0.3048)
			(stroke
				(width 0.1)
				(type default)
			)
			(layer "B.Fab")
		)
		(fp_line
			(start -0.12065 -0.3048)
			(end -0.67945 -0.3048)
			(stroke
				(width 0.1)
				(type default)
			)
			(layer "B.Fab")
		)
		(fp_line
			(start -0.12065 -0.2794)
			(end -0.12065 -0.3048)
			(stroke
				(width 0.1)
				(type default)
			)
			(layer "B.Fab")
		)
		(fp_line
			(start -0.120396 0.2794)
			(end 0.12065 0.2794)
			(stroke
				(width 0.1)
				(type default)
			)
			(layer "B.Fab")
		)
		(fp_line
			(start -0.120396 0.3048)
			(end -0.120396 0.2794)
			(stroke
				(width 0.1)
				(type default)
			)
			(layer "B.Fab")
		)
		(fp_line
			(start 0.12065 -0.305054)
			(end 0.12065 -0.2794)
			(stroke
				(width 0.1)
				(type default)
			)
			(layer "B.Fab")
		)
		(fp_line
			(start 0.12065 -0.2794)
			(end -0.12065 -0.2794)
			(stroke
				(width 0.1)
				(type default)
			)
			(layer "B.Fab")
		)
		(fp_line
			(start 0.12065 0.2794)
			(end 0.12065 0.3048)
			(stroke
				(width 0.1)
				(type default)
			)
			(layer "B.Fab")
		)
		(fp_line
			(start 0.12065 0.3048)
			(end 0.67945 0.3048)
			(stroke
				(width 0.1)
				(type default)
			)
			(layer "B.Fab")
		)
		(fp_line
			(start 0.67945 -0.305054)
			(end 0.12065 -0.305054)
			(stroke
				(width 0.1)
				(type default)
			)
			(layer "B.Fab")
		)
		(fp_line
			(start 0.67945 0.3048)
			(end 0.67945 -0.305054)
			(stroke
				(width 0.1)
				(type default)
			)
			(layer "B.Fab")
		)
		(pad "1" smd rect
			(at 0.40005 0)
			(size 0.4572 0.508)
			(layers "B.Cu" "B.Mask" "B.Paste")
			(net "PVDD_33_S5_ADC")
		)
		(pad "2" smd rect
			(at -0.40005 0)
			(size 0.4572 0.508)
			(layers "B.Cu" "B.Mask" "B.Paste")
			(net "PVDD_33_S5_ADC_TIC")
		)
	)
	(footprint ""
		(layer "B.Cu")
		(at 413.946086 -396.393162 -90)
		(property "Reference" "C775"
			(at 0 0 90)
			(layer "B.SilkS")
			(hide yes)
			(effects
				(font
					(size 1.27 1.27)
				)
				(justify mirror)
			)
		)
		(property "Value" ""
			(at 0 0 90)
			(layer "B.Fab")
			(effects
				(font
					(size 1.27 1.27)
				)
				(justify mirror)
			)
		)
		(duplicate_pad_numbers_are_jumpers no)
		(fp_line
			(start -0.299974 0.150114)
			(end 0.299974 0.150114)
			(stroke
				(width 0.1)
				(type default)
			)
			(layer "B.Fab")
		)
		(fp_line
			(start 0.299974 0.150114)
			(end 0.299974 -0.150114)
			(stroke
				(width 0.1)
				(type default)
			)
			(layer "B.Fab")
		)
		(fp_line
			(start -0.299974 -0.150114)
			(end -0.299974 0.150114)
			(stroke
				(width 0.1)
				(type default)
			)
			(layer "B.Fab")
		)
		(fp_line
			(start 0.299974 -0.150114)
			(end -0.299974 -0.150114)
			(stroke
				(width 0.1)
				(type default)
			)
			(layer "B.Fab")
		)
		(pad "1" smd rect
			(at 0.2667 0 90)
			(size 0.3048 0.381)
			(layers "B.Cu" "B.Mask" "B.Paste")
			(net "P1V8_CPU0_RT2_1A_1D")
		)
		(pad "2" smd rect
			(at -0.2667 0 90)
			(size 0.3048 0.381)
			(layers "B.Cu" "B.Mask" "B.Paste")
			(net "GND")
		)
	)
	(footprint ""
		(layer "B.Cu")
		(at 157.806136 -386.766562 90)
		(property "Reference" "C375"
			(at 0 0 90)
			(layer "B.SilkS")
			(hide yes)
			(effects
				(font
					(size 1.27 1.27)
				)
				(justify mirror)
			)
		)
		(property "Value" ""
			(at 0 0 90)
			(layer "B.Fab")
			(effects
				(font
					(size 1.27 1.27)
				)
				(justify mirror)
			)
		)
		(duplicate_pad_numbers_are_jumpers no)
		(fp_line
			(start 0.299974 -0.150114)
			(end -0.299974 -0.150114)
			(stroke
				(width 0.1)
				(type default)
			)
			(layer "B.Fab")
		)
		(fp_line
			(start -0.299974 -0.150114)
			(end -0.299974 0.150114)
			(stroke
				(width 0.1)
				(type default)
			)
			(layer "B.Fab")
		)
		(fp_line
			(start 0.299974 0.150114)
			(end 0.299974 -0.150114)
			(stroke
				(width 0.1)
				(type default)
			)
			(layer "B.Fab")
		)
		(fp_line
			(start -0.299974 0.150114)
			(end 0.299974 0.150114)
			(stroke
				(width 0.1)
				(type default)
			)
			(layer "B.Fab")
		)
		(pad "1" smd rect
			(at 0.2667 0 270)
			(size 0.3048 0.381)
			(layers "B.Cu" "B.Mask" "B.Paste")
			(net "P1V8_CPU1_RT2_1A_1D")
		)
		(pad "2" smd rect
			(at -0.2667 0 270)
			(size 0.3048 0.381)
			(layers "B.Cu" "B.Mask" "B.Paste")
			(net "GND")
		)
	)
	(footprint ""
		(layer "B.Cu")
		(at 376.478546 -395.148562 90)
		(property "Reference" "C1007"
			(at 0 0 90)
			(layer "B.SilkS")
			(hide yes)
			(effects
				(font
					(size 1.27 1.27)
				)
				(justify mirror)
			)
		)
		(property "Value" ""
			(at 0 0 90)
			(layer "B.Fab")
			(effects
				(font
					(size 1.27 1.27)
				)
				(justify mirror)
			)
		)
		(duplicate_pad_numbers_are_jumpers no)
		(fp_line
			(start 0.299974 -0.150114)
			(end -0.299974 -0.150114)
			(stroke
				(width 0.1)
				(type default)
			)
			(layer "B.Fab")
		)
		(fp_line
			(start -0.299974 -0.150114)
			(end -0.299974 0.150114)
			(stroke
				(width 0.1)
				(type default)
			)
			(layer "B.Fab")
		)
		(fp_line
			(start 0.299974 0.150114)
			(end 0.299974 -0.150114)
			(stroke
				(width 0.1)
				(type default)
			)
			(layer "B.Fab")
		)
		(fp_line
			(start -0.299974 0.150114)
			(end 0.299974 0.150114)
			(stroke
				(width 0.1)
				(type default)
			)
			(layer "B.Fab")
		)
		(pad "1" smd rect
			(at 0.2667 0 270)
			(size 0.3048 0.381)
			(layers "B.Cu" "B.Mask" "B.Paste")
			(net "P0V9_CPU0_RT_2D")
		)
		(pad "2" smd rect
			(at -0.2667 0 270)
			(size 0.3048 0.381)
			(layers "B.Cu" "B.Mask" "B.Paste")
			(net "GND")
		)
	)
	(footprint ""
		(layer "B.Cu")
		(at 92.046298 -388.011162 -90)
		(property "Reference" "C311"
			(at 0 0 90)
			(layer "B.SilkS")
			(hide yes)
			(effects
				(font
					(size 1.27 1.27)
				)
				(justify mirror)
			)
		)
		(property "Value" ""
			(at 0 0 90)
			(layer "B.Fab")
			(effects
				(font
					(size 1.27 1.27)
				)
				(justify mirror)
			)
		)
		(duplicate_pad_numbers_are_jumpers no)
		(fp_line
			(start -0.299974 0.150114)
			(end 0.299974 0.150114)
			(stroke
				(width 0.1)
				(type default)
			)
			(layer "B.Fab")
		)
		(fp_line
			(start 0.299974 0.150114)
			(end 0.299974 -0.150114)
			(stroke
				(width 0.1)
				(type default)
			)
			(layer "B.Fab")
		)
		(fp_line
			(start -0.299974 -0.150114)
			(end -0.299974 0.150114)
			(stroke
				(width 0.1)
				(type default)
			)
			(layer "B.Fab")
		)
		(fp_line
			(start 0.299974 -0.150114)
			(end -0.299974 -0.150114)
			(stroke
				(width 0.1)
				(type default)
			)
			(layer "B.Fab")
		)
		(pad "1" smd rect
			(at 0.2667 0 90)
			(size 0.3048 0.381)
			(layers "B.Cu" "B.Mask" "B.Paste")
			(net "P0V9_CPU1_RT_2D")
		)
		(pad "2" smd rect
			(at -0.2667 0 90)
			(size 0.3048 0.381)
			(layers "B.Cu" "B.Mask" "B.Paste")
			(net "GND")
		)
	)
	(footprint ""
		(layer "B.Cu")
		(at 458.346302 -407.877264 180)
		(property "Reference" "PC6583"
			(at 0 0 0)
			(layer "B.SilkS")
			(hide yes)
			(effects
				(font
					(size 1.27 1.27)
				)
				(justify mirror)
			)
		)
		(property "Value" ""
			(at 0 0 0)
			(layer "B.Fab")
			(effects
				(font
					(size 1.27 1.27)
				)
				(justify mirror)
			)
		)
		(duplicate_pad_numbers_are_jumpers no)
		(fp_line
			(start 1.524 0.762)
			(end 1.524 -0.762)
			(stroke
				(width 0.1524)
				(type default)
			)
			(layer "B.SilkS")
		)
		(fp_line
			(start 1.524 -0.762)
			(end -1.524 -0.762)
			(stroke
				(width 0.1524)
				(type default)
			)
			(layer "B.SilkS")
		)
		(fp_line
			(start -1.524 0.762)
			(end 1.524 0.762)
			(stroke
				(width 0.1524)
				(type default)
			)
			(layer "B.SilkS")
		)
		(fp_line
			(start -1.524 -0.762)
			(end -1.524 0.762)
			(stroke
				(width 0.1524)
				(type default)
			)
			(layer "B.SilkS")
		)
		(fp_line
			(start 1.1049 0.724916)
			(end -1.1049 0.724916)
			(stroke
				(width 0.1)
				(type default)
			)
			(layer "B.Fab")
		)
		(fp_line
			(start 1.1049 -0.724916)
			(end 1.1049 0.724916)
			(stroke
				(width 0.1)
				(type default)
			)
			(layer "B.Fab")
		)
		(fp_line
			(start -1.1049 0.724916)
			(end -1.1049 -0.724916)
			(stroke
				(width 0.1)
				(type default)
			)
			(layer "B.Fab")
		)
		(fp_line
			(start -1.1049 -0.724916)
			(end 1.1049 -0.724916)
			(stroke
				(width 0.1)
				(type default)
			)
			(layer "B.Fab")
		)
		(pad "1" smd rect
			(at 0.889 0 180)
			(size 1.016 1.27)
			(layers "B.Cu" "B.Mask" "B.Paste")
			(net "SW_P12V_AUX_P0V9_RETIMER_CPU0_FLT")
		)
		(pad "2" smd rect
			(at -0.889 0 180)
			(size 1.016 1.27)
			(layers "B.Cu" "B.Mask" "B.Paste")
			(net "GND")
		)
	)
	(footprint ""
		(layer "B.Cu")
		(at 348.185486 -416.899344 90)
		(property "Reference" "C6562"
			(at 0 0 90)
			(layer "B.SilkS")
			(hide yes)
			(effects
				(font
					(size 1.27 1.27)
				)
				(justify mirror)
			)
		)
		(property "Value" ""
			(at 0 0 90)
			(layer "B.Fab")
			(effects
				(font
					(size 1.27 1.27)
				)
				(justify mirror)
			)
		)
		(duplicate_pad_numbers_are_jumpers no)
		(fp_line
			(start 0.299974 -0.150114)
			(end -0.299974 -0.150114)
			(stroke
				(width 0.1)
				(type default)
			)
			(layer "B.Fab")
		)
		(fp_line
			(start -0.299974 -0.150114)
			(end -0.299974 0.150114)
			(stroke
				(width 0.1)
				(type default)
			)
			(layer "B.Fab")
		)
		(fp_line
			(start 0.299974 0.150114)
			(end 0.299974 -0.150114)
			(stroke
				(width 0.1)
				(type default)
			)
			(layer "B.Fab")
		)
		(fp_line
			(start -0.299974 0.150114)
			(end 0.299974 0.150114)
			(stroke
				(width 0.1)
				(type default)
			)
			(layer "B.Fab")
		)
		(pad "1" smd rect
			(at 0.2667 0 270)
			(size 0.3048 0.381)
			(layers "B.Cu" "B.Mask" "B.Paste")
			(net "P5E_CPU0_P1_TX_BUF_C_DN<14>")
		)
		(pad "2" smd rect
			(at -0.2667 0 270)
			(size 0.3048 0.381)
			(layers "B.Cu" "B.Mask" "B.Paste")
			(net "P5E_CPU0_P1_TX_BUF_DN<14>")
		)
	)
	(footprint ""
		(layer "B.Cu")
		(at 400.761962 -313.782964 180)
		(property "Reference" "R433"
			(at 0 0 0)
			(layer "B.SilkS")
			(hide yes)
			(effects
				(font
					(size 1.27 1.27)
				)
				(justify mirror)
			)
		)
		(property "Value" ""
			(at 0 0 0)
			(layer "B.Fab")
			(effects
				(font
					(size 1.27 1.27)
				)
				(justify mirror)
			)
		)
		(duplicate_pad_numbers_are_jumpers no)
		(fp_line
			(start 0.7874 0.4064)
			(end 0.7874 -0.4064)
			(stroke
				(width 0.1524)
				(type default)
			)
			(layer "B.SilkS")
		)
		(fp_line
			(start 0.7874 -0.4064)
			(end -0.7874 -0.4064)
			(stroke
				(width 0.1524)
				(type default)
			)
			(layer "B.SilkS")
		)
		(fp_line
			(start -0.7874 0.4064)
			(end 0.7874 0.4064)
			(stroke
				(width 0.1524)
				(type default)
			)
			(layer "B.SilkS")
		)
		(fp_line
			(start -0.7874 -0.4064)
			(end -0.7874 0.4064)
			(stroke
				(width 0.1524)
				(type default)
			)
			(layer "B.SilkS")
		)
		(fp_line
			(start 0.67945 0.3048)
			(end 0.67945 -0.305054)
			(stroke
				(width 0.1)
				(type default)
			)
			(layer "B.Fab")
		)
		(fp_line
			(start 0.67945 -0.305054)
			(end 0.12065 -0.305054)
			(stroke
				(width 0.1)
				(type default)
			)
			(layer "B.Fab")
		)
		(fp_line
			(start 0.12065 0.3048)
			(end 0.67945 0.3048)
			(stroke
				(width 0.1)
				(type default)
			)
			(layer "B.Fab")
		)
		(fp_line
			(start 0.12065 0.2794)
			(end 0.12065 0.3048)
			(stroke
				(width 0.1)
				(type default)
			)
			(layer "B.Fab")
		)
		(fp_line
			(start 0.12065 -0.2794)
			(end -0.12065 -0.2794)
			(stroke
				(width 0.1)
				(type default)
			)
			(layer "B.Fab")
		)
		(fp_line
			(start 0.12065 -0.305054)
			(end 0.12065 -0.2794)
			(stroke
				(width 0.1)
				(type default)
			)
			(layer "B.Fab")
		)
		(fp_line
			(start -0.120396 0.3048)
			(end -0.120396 0.2794)
			(stroke
				(width 0.1)
				(type default)
			)
			(layer "B.Fab")
		)
		(fp_line
			(start -0.120396 0.2794)
			(end 0.12065 0.2794)
			(stroke
				(width 0.1)
				(type default)
			)
			(layer "B.Fab")
		)
		(fp_line
			(start -0.12065 -0.2794)
			(end -0.12065 -0.3048)
			(stroke
				(width 0.1)
				(type default)
			)
			(layer "B.Fab")
		)
		(fp_line
			(start -0.12065 -0.3048)
			(end -0.67945 -0.3048)
			(stroke
				(width 0.1)
				(type default)
			)
			(layer "B.Fab")
		)
		(fp_line
			(start -0.67945 0.3048)
			(end -0.120396 0.3048)
			(stroke
				(width 0.1)
				(type default)
			)
			(layer "B.Fab")
		)
		(fp_line
			(start -0.67945 -0.3048)
			(end -0.67945 0.3048)
			(stroke
				(width 0.1)
				(type default)
			)
			(layer "B.Fab")
		)
		(pad "1" smd circle
			(at 0.40005 0)
			(size 0 0)
			(layers "B.Cu" "B.Mask" "B.Paste")
			(net "XTAL_CPU0_X32K_X1")
		)
		(pad "2" smd circle
			(at -0.40005 0)
			(size 0 0)
			(layers "B.Cu" "B.Mask" "B.Paste")
			(net "XTAL_CPU0_X32K_X2")
		)
	)
)
